# T6G (Grand Teton) — schematic netlist excerpt (pin names and nets, part order shuffled) for the footprints in the layout excerpt that follows; sources: Cadence DE-HDL packaged netlist, KiCad conversion of 04192023_DAF0TMB3IC0_F0TG_MB_C_brd_V02_OCP.brd

R389  Q_RES  2.2K 5% CHIP  pkg 0402LF  page 27 : A = P3V3_AUX ; B = CPU0_SP5R4
C924  Q_CAP_DIFFBUS  DIFF BUS_0.22UF 6.3V 20% X6S  pkg C0201  page 63 : \1\ = P5E_CPU0_P0_TX_C_DN<4> ; \2\ = P5E_CPU0_P0_TX_DN<4>
D78  Q_LED  IC  pkg SMLF  page 255 : A = LED_PWRGD_PVDD11_S3_P0_R ; C = LED_PWRGD_PVDD11_S3_P0_D

(kicad_pcb
	(version 20260206)
	(generator "pcbnew")
	(generator_version "10.0")
	(general
		(thickness 1.6)
		(legacy_teardrops no)
	)
	(paper "A4")
	(title_block
		(title "04192023_DAF0TMB3IC0_F0TG_MB_C_brd_V02_OCP.brd")
		(comment 1 "Grand Teton / footprints 3921-3923 of 8354")
	)
	(layers
		(0 "F.Cu" signal "TOP")
		(4 "In1.Cu" signal "GND")
		(6 "In2.Cu" signal "IN1")
		(8 "In3.Cu" signal "GND1")
		(10 "In4.Cu" signal "IN2")
		(12 "In5.Cu" signal "GND2")
		(14 "In6.Cu" signal "IN3")
		(16 "In7.Cu" signal "GND3")
		(18 "In8.Cu" signal "VCC")
		(20 "In9.Cu" signal "VCC1")
		(22 "In10.Cu" signal "GND4")
		(24 "In11.Cu" signal "IN4")
		(26 "In12.Cu" signal "GND5")
		(28 "In13.Cu" signal "IN5")
		(30 "In14.Cu" signal "GND6")
		(32 "In15.Cu" signal "IN6")
		(34 "In16.Cu" signal "GND7")
		(2 "B.Cu" signal "BOTTOM")
		(9 "F.Adhes" user "F.Adhesive")
		(11 "B.Adhes" user "B.Adhesive")
		(13 "F.Paste" user "Package Geometry/Pastemask Top")
		(15 "B.Paste" user "Package Geometry/Pastemask Bottom")
		(5 "F.SilkS" user "Ref Des/Silkscreen Top")
		(7 "B.SilkS" user "Ref Des/Silkscreen Bottom")
		(1 "F.Mask" user "Board Geometry/Soldermask Top")
		(3 "B.Mask" user "Board Geometry/Soldermask Bottom")
		(17 "Dwgs.User" user "User.Drawings")
		(19 "Cmts.User" user "User.Comments")
		(21 "Eco1.User" user "User.Eco1")
		(23 "Eco2.User" user "User.Eco2")
		(25 "Edge.Cuts" user "Board Geometry/Outline")
		(27 "Margin" user)
		(31 "F.CrtYd" user "Package Geometry/Place Bound Top")
		(29 "B.CrtYd" user "Package Geometry/Place Bound Bottom")
		(35 "F.Fab" user "Ref Des/Assembly Top")
		(33 "B.Fab" user "Ref Des/Assembly Bottom")
	)
	(footprint ""
		(layer "F.Cu")
		(at 393.363958 -322.627752 180)
		(property "Reference" "R389"
			(at 0 0 180)
			(layer "F.SilkS")
			(hide yes)
			(effects
				(font
					(size 1.27 1.27)
				)
			)
		)
		(property "Value" ""
			(at 0 0 180)
			(layer "F.Fab")
			(effects
				(font
					(size 1.27 1.27)
				)
			)
		)
		(duplicate_pad_numbers_are_jumpers no)
		(fp_line
			(start 0.7874 0.4064)
			(end -0.7874 0.4064)
			(stroke
				(width 0.1524)
				(type default)
			)
			(layer "F.SilkS")
		)
		(fp_line
			(start 0.7874 -0.4064)
			(end 0.7874 0.4064)
			(stroke
				(width 0.1524)
				(type default)
			)
			(layer "F.SilkS")
		)
		(fp_line
			(start -0.7874 0.4064)
			(end -0.7874 -0.4064)
			(stroke
				(width 0.1524)
				(type default)
			)
			(layer "F.SilkS")
		)
		(fp_line
			(start -0.7874 -0.4064)
			(end 0.7874 -0.4064)
			(stroke
				(width 0.1524)
				(type default)
			)
			(layer "F.SilkS")
		)
		(fp_line
			(start 0.67945 0.3048)
			(end 0.120396 0.3048)
			(stroke
				(width 0.1)
				(type default)
			)
			(layer "F.Fab")
		)
		(fp_line
			(start 0.67945 -0.3048)
			(end 0.67945 0.3048)
			(stroke
				(width 0.1)
				(type default)
			)
			(layer "F.Fab")
		)
		(fp_line
			(start 0.12065 -0.2794)
			(end 0.12065 -0.3048)
			(stroke
				(width 0.1)
				(type default)
			)
			(layer "F.Fab")
		)
		(fp_line
			(start 0.12065 -0.3048)
			(end 0.67945 -0.3048)
			(stroke
				(width 0.1)
				(type default)
			)
			(layer "F.Fab")
		)
		(fp_line
			(start 0.120396 0.3048)
			(end 0.120396 0.2794)
			(stroke
				(width 0.1)
				(type default)
			)
			(layer "F.Fab")
		)
		(fp_line
			(start 0.120396 0.2794)
			(end -0.12065 0.2794)
			(stroke
				(width 0.1)
				(type default)
			)
			(layer "F.Fab")
		)
		(fp_line
			(start -0.12065 0.3048)
			(end -0.67945 0.3048)
			(stroke
				(width 0.1)
				(type default)
			)
			(layer "F.Fab")
		)
		(fp_line
			(start -0.12065 0.2794)
			(end -0.12065 0.3048)
			(stroke
				(width 0.1)
				(type default)
			)
			(layer "F.Fab")
		)
		(fp_line
			(start -0.12065 -0.2794)
			(end 0.12065 -0.2794)
			(stroke
				(width 0.1)
				(type default)
			)
			(layer "F.Fab")
		)
		(fp_line
			(start -0.12065 -0.305054)
			(end -0.12065 -0.2794)
			(stroke
				(width 0.1)
				(type default)
			)
			(layer "F.Fab")
		)
		(fp_line
			(start -0.67945 0.3048)
			(end -0.67945 -0.305054)
			(stroke
				(width 0.1)
				(type default)
			)
			(layer "F.Fab")
		)
		(fp_line
			(start -0.67945 -0.305054)
			(end -0.12065 -0.305054)
			(stroke
				(width 0.1)
				(type default)
			)
			(layer "F.Fab")
		)
		(pad "1" smd circle
			(at -0.40005 0 180)
			(size 0 0)
			(layers "F.Cu" "F.Mask" "F.Paste")
			(net "P3V3_AUX")
		)
		(pad "2" smd circle
			(at 0.40005 0 180)
			(size 0 0)
			(layers "F.Cu" "F.Mask" "F.Paste")
			(net "CPU0_SP5R4")
		)
	)
	(footprint ""
		(layer "F.Cu")
		(at 332.763876 -70.098412 90)
		(property "Reference" "D78"
			(at -3.934714 -0.691642 90)
			(unlocked yes)
			(layer "F.SilkS")
			(effects
				(font
					(size 0.7874 0.5842)
					(thickness 0.1524)
				)
				(justify left)
			)
		)
		(property "Value" ""
			(at 0 0 90)
			(layer "F.Fab")
			(effects
				(font
					(size 1.27 1.27)
				)
			)
		)
		(duplicate_pad_numbers_are_jumpers no)
		(fp_line
			(start 1.16078 -0.4826)
			(end 1.16078 0.4826)
			(stroke
				(width 0.1524)
				(type default)
			)
			(layer "F.SilkS")
		)
		(fp_line
			(start 1.03378 -0.4826)
			(end 1.03378 0.4826)
			(stroke
				(width 0.1524)
				(type default)
			)
			(layer "F.SilkS")
		)
		(fp_line
			(start 0.90678 -0.4826)
			(end 0.90678 0.4826)
			(stroke
				(width 0.1524)
				(type default)
			)
			(layer "F.SilkS")
		)
		(fp_line
			(start -0.64008 -0.4826)
			(end 1.16078 -0.4826)
			(stroke
				(width 0.1524)
				(type default)
			)
			(layer "F.SilkS")
		)
		(fp_line
			(start -0.79248 -0.4826)
			(end 1.03378 -0.4826)
			(stroke
				(width 0.1524)
				(type default)
			)
			(layer "F.SilkS")
		)
		(fp_line
			(start -0.89408 -0.4826)
			(end 0.90678 -0.4826)
			(stroke
				(width 0.1524)
				(type default)
			)
			(layer "F.SilkS")
		)
		(fp_line
			(start 1.16078 0.4826)
			(end -0.64008 0.4826)
			(stroke
				(width 0.1524)
				(type default)
			)
			(layer "F.SilkS")
		)
		(fp_line
			(start 1.03378 0.4826)
			(end -0.79248 0.4826)
			(stroke
				(width 0.1524)
				(type default)
			)
			(layer "F.SilkS")
		)
		(fp_line
			(start 0.90678 0.4826)
			(end -0.90678 0.4826)
			(stroke
				(width 0.1524)
				(type default)
			)
			(layer "F.SilkS")
		)
		(fp_line
			(start -0.90678 0.4826)
			(end -0.90678 -0.4699)
			(stroke
				(width 0.1524)
				(type default)
			)
			(layer "F.SilkS")
		)
		(fp_line
			(start 0.499872 -0.249936)
			(end 0.499872 0.249936)
			(stroke
				(width 0.1)
				(type default)
			)
			(layer "F.Fab")
		)
		(fp_line
			(start -0.499872 -0.249936)
			(end 0.499872 -0.249936)
			(stroke
				(width 0.1)
				(type default)
			)
			(layer "F.Fab")
		)
		(fp_line
			(start 0.499872 0.249936)
			(end -0.499872 0.249936)
			(stroke
				(width 0.1)
				(type default)
			)
			(layer "F.Fab")
		)
		(fp_line
			(start -0.499872 0.249936)
			(end -0.499872 -0.249936)
			(stroke
				(width 0.1)
				(type default)
			)
			(layer "F.Fab")
		)
		(pad "A" smd rect
			(at -0.47498 0 90)
			(size 0.6096 0.7112)
			(layers "F.Cu" "F.Mask" "F.Paste")
			(net "LED_PWRGD_PVDD11_S3_P0_R")
		)
		(pad "C" smd rect
			(at 0.47498 0 90)
			(size 0.6096 0.7112)
			(layers "F.Cu" "F.Mask" "F.Paste")
			(net "LED_PWRGD_PVDD11_S3_P0_D")
		)
	)
	(footprint ""
		(layer "F.Cu")
		(at 305.009296 -383.88163 -90)
		(property "Reference" "C924"
			(at 0 0 270)
			(layer "F.SilkS")
			(hide yes)
			(effects
				(font
					(size 1.27 1.27)
				)
			)
		)
		(property "Value" ""
			(at 0 0 270)
			(layer "F.Fab")
			(effects
				(font
					(size 1.27 1.27)
				)
			)
		)
		(duplicate_pad_numbers_are_jumpers no)
		(fp_line
			(start -0.299974 0.150114)
			(end -0.299974 -0.150114)
			(stroke
				(width 0.1)
				(type default)
			)
			(layer "F.Fab")
		)
		(fp_line
			(start 0.299974 0.150114)
			(end -0.299974 0.150114)
			(stroke
				(width 0.1)
				(type default)
			)
			(layer "F.Fab")
		)
		(fp_line
			(start -0.299974 -0.150114)
			(end 0.299974 -0.150114)
			(stroke
				(width 0.1)
				(type default)
			)
			(layer "F.Fab")
		)
		(fp_line
			(start 0.299974 -0.150114)
			(end 0.299974 0.150114)
			(stroke
				(width 0.1)
				(type default)
			)
			(layer "F.Fab")
		)
		(pad "1" smd rect
			(at -0.2667 0 270)
			(size 0.3048 0.381)
			(layers "F.Cu" "F.Mask" "F.Paste")
			(net "P5E_CPU0_P0_TX_C_DN<4>")
		)
		(pad "2" smd rect
			(at 0.2667 0 270)
			(size 0.3048 0.381)
			(layers "F.Cu" "F.Mask" "F.Paste")
			(net "P5E_CPU0_P0_TX_DN<4>")
		)
	)
)
